# T6G (Grand Teton) — schematic netlist excerpt (pin names and nets, part order shuffled) for the footprints in the layout excerpt that follows; sources: Cadence DE-HDL packaged netlist, KiCad conversion of 04192023_DAF0TMB3IC0_F0TG_MB_C_brd_V02_OCP.brd

H111  GND_HOLE  EMPTY  pkg TH  page 230
  GND2  = GND
  GND3  = GND
  GND4  = GND
  GND5  = GND
  GND6  = GND
  GND7  = GND
  GND8  = GND
  GND9  = GND

(kicad_pcb
	(version 20260206)
	(generator "pcbnew")
	(generator_version "10.0")
	(general
		(thickness 1.6)
		(legacy_teardrops no)
	)
	(paper "A4")
	(title_block
		(title "04192023_DAF0TMB3IC0_F0TG_MB_C_brd_V02_OCP.brd")
		(comment 1 "Grand Teton / footprints 1102-1102 of 8354")
	)
	(layers
		(0 "F.Cu" signal "TOP")
		(4 "In1.Cu" signal "GND")
		(6 "In2.Cu" signal "IN1")
		(8 "In3.Cu" signal "GND1")
		(10 "In4.Cu" signal "IN2")
		(12 "In5.Cu" signal "GND2")
		(14 "In6.Cu" signal "IN3")
		(16 "In7.Cu" signal "GND3")
		(18 "In8.Cu" signal "VCC")
		(20 "In9.Cu" signal "VCC1")
		(22 "In10.Cu" signal "GND4")
		(24 "In11.Cu" signal "IN4")
		(26 "In12.Cu" signal "GND5")
		(28 "In13.Cu" signal "IN5")
		(30 "In14.Cu" signal "GND6")
		(32 "In15.Cu" signal "IN6")
		(34 "In16.Cu" signal "GND7")
		(2 "B.Cu" signal "BOTTOM")
		(9 "F.Adhes" user "F.Adhesive")
		(11 "B.Adhes" user "B.Adhesive")
		(13 "F.Paste" user "Package Geometry/Pastemask Top")
		(15 "B.Paste" user "Package Geometry/Pastemask Bottom")
		(5 "F.SilkS" user "Ref Des/Silkscreen Top")
		(7 "B.SilkS" user "Ref Des/Silkscreen Bottom")
		(1 "F.Mask" user "Board Geometry/Soldermask Top")
		(3 "B.Mask" user "Board Geometry/Soldermask Bottom")
		(17 "Dwgs.User" user "User.Drawings")
		(19 "Cmts.User" user "User.Comments")
		(21 "Eco1.User" user "User.Eco1")
		(23 "Eco2.User" user "User.Eco2")
		(25 "Edge.Cuts" user "Board Geometry/Outline")
		(27 "Margin" user)
		(31 "F.CrtYd" user "Package Geometry/Place Bound Top")
		(29 "B.CrtYd" user "Package Geometry/Place Bound Bottom")
		(35 "F.Fab" user "Ref Des/Assembly Top")
		(33 "B.Fab" user "Ref Des/Assembly Bottom")
	)
	(footprint ""
		(layer "F.Cu")
		(at 213.67496 -360.764074)
		(property "Reference" "H111"
			(at -8.086852 -7.844028 0)
			(unlocked yes)
			(layer "F.SilkS")
			(effects
				(font
					(size 0.7874 0.5842)
					(thickness 0.1524)
				)
				(justify left)
			)
		)
		(property "Value" ""
			(at 0 0 0)
			(layer "F.Fab")
			(effects
				(font
					(size 1.27 1.27)
				)
			)
		)
		(duplicate_pad_numbers_are_jumpers no)
		(fp_circle
			(center 0 0)
			(end 7.999984 0)
			(stroke
				(width 0.1524)
				(type default)
			)
			(fill no)
			(layer "F.SilkS")
		)
		(fp_circle
			(center 0 0)
			(end 7.999984 0)
			(stroke
				(width 0.1524)
				(type default)
			)
			(fill no)
			(layer "B.SilkS")
		)
		(fp_circle
			(center 0 0)
			(end 7.999984 0)
			(stroke
				(width 0.1)
				(type default)
			)
			(fill no)
			(layer "B.Fab")
		)
		(fp_circle
			(center 0 0)
			(end 7.999984 0)
			(stroke
				(width 0.1)
				(type default)
			)
			(fill no)
			(layer "F.Fab")
		)
		(pad "" np_thru_hole circle
			(at 0 0)
			(size 4.0132 4.0132)
			(drill 4.0132)
			(layers "*.Cu" "*.Mask")
			(clearance 0.381)
			(thermal_gap 0.381)
		)
		(pad "2" thru_hole circle
			(at 3.2639 0)
			(size 0.9144 0.9144)
			(drill 0.5588)
			(layers "*.Cu" "*.Mask")
			(remove_unused_layers no)
			(net "GND")
			(clearance 0.0762)
			(thermal_gap 0.0762)
		)
		(pad "3" thru_hole circle
			(at 2.307844 -2.307844)
			(size 0.9144 0.9144)
			(drill 0.5588)
			(layers "*.Cu" "*.Mask")
			(remove_unused_layers no)
			(net "GND")
			(clearance 0.0762)
			(thermal_gap 0.0762)
		)
		(pad "4" thru_hole circle
			(at 0 -3.2639)
			(size 0.9144 0.9144)
			(drill 0.5588)
			(layers "*.Cu" "*.Mask")
			(remove_unused_layers no)
			(net "GND")
			(clearance 0.0762)
			(thermal_gap 0.0762)
		)
		(pad "5" thru_hole circle
			(at -2.307844 -2.307844)
			(size 0.9144 0.9144)
			(drill 0.5588)
			(layers "*.Cu" "*.Mask")
			(remove_unused_layers no)
			(net "GND")
			(clearance 0.0762)
			(thermal_gap 0.0762)
		)
		(pad "6" thru_hole circle
			(at -3.2639 0)
			(size 0.9144 0.9144)
			(drill 0.5588)
			(layers "*.Cu" "*.Mask")
			(remove_unused_layers no)
			(net "GND")
			(clearance 0.0762)
			(thermal_gap 0.0762)
		)
		(pad "7" thru_hole circle
			(at -2.307844 2.307844)
			(size 0.9144 0.9144)
			(drill 0.5588)
			(layers "*.Cu" "*.Mask")
			(remove_unused_layers no)
			(net "GND")
			(clearance 0.0762)
			(thermal_gap 0.0762)
		)
		(pad "8" thru_hole circle
			(at 0 3.2639)
			(size 0.9144 0.9144)
			(drill 0.5588)
			(layers "*.Cu" "*.Mask")
			(remove_unused_layers no)
			(net "GND")
			(clearance 0.0762)
			(thermal_gap 0.0762)
		)
		(pad "9" thru_hole circle
			(at 2.307844 2.307844)
			(size 0.9144 0.9144)
			(drill 0.5588)
			(layers "*.Cu" "*.Mask")
			(remove_unused_layers no)
			(net "GND")
			(clearance 0.0762)
			(thermal_gap 0.0762)
		)
		(zone
			(layer "F.Cu")
			(hatch none 0.5)
			(connect_pads
				(clearance 0)
			)
			(min_thickness 0.25)
			(keepout
				(tracks not_allowed)
				(vias allowed)
				(pads allowed)
				(copperpour not_allowed)
				(footprints allowed)
			)
			(placement
				(enabled no)
				(sheetname "")
			)
			(fill
				(thermal_gap 0.5)
				(thermal_bridge_width 0.5)
				(island_removal_mode 0)
			)
			(polygon
				(pts
					(arc
						(start 213.67496 -356.496874)
						(mid 209.40776 -360.764074)
						(end 213.67496 -365.031274)
					)
					(arc
						(start 213.67496 -368.764058)
						(mid 208.018117 -366.420917)
						(end 205.674976 -360.764074)
					)
					(arc
						(start 205.674976 -360.764074)
						(mid 208.018117 -355.107231)
						(end 213.67496 -352.76409)
					)
				)
			)
		)
		(zone
			(layer "F.Cu")
			(hatch none 0.5)
			(connect_pads
				(clearance 0)
			)
			(min_thickness 0.25)
			(keepout
				(tracks not_allowed)
				(vias allowed)
				(pads allowed)
				(copperpour not_allowed)
				(footprints allowed)
			)
			(placement
				(enabled no)
				(sheetname "")
			)
			(fill
				(thermal_gap 0.5)
				(thermal_bridge_width 0.5)
				(island_removal_mode 0)
			)
			(polygon
				(pts
					(arc
						(start 213.67496 -356.496874)
						(mid 217.94216 -360.764074)
						(end 213.67496 -365.031274)
					)
					(arc
						(start 213.67496 -368.764058)
						(mid 219.331803 -366.420917)
						(end 221.674944 -360.764074)
					)
					(arc
						(start 221.674944 -360.764074)
						(mid 219.331803 -355.107231)
						(end 213.67496 -352.76409)
					)
				)
			)
		)
		(zone
			(layers "F.Cu" "B.Cu" "In1.Cu" "In2.Cu" "In3.Cu" "In4.Cu" "In5.Cu" "In6.Cu"
				"In7.Cu" "In8.Cu" "In9.Cu" "In10.Cu" "In11.Cu" "In12.Cu" "In13.Cu" "In14.Cu"
				"In15.Cu" "In16.Cu"
			)
			(hatch none 0.5)
			(connect_pads
				(clearance 0)
			)
			(min_thickness 0.25)
			(keepout
				(tracks not_allowed)
				(vias allowed)
				(pads allowed)
				(copperpour not_allowed)
				(footprints allowed)
			)
			(placement
				(enabled no)
				(sheetname "")
			)
			(fill
				(thermal_gap 0.5)
				(thermal_bridge_width 0.5)
				(island_removal_mode 0)
			)
			(polygon
				(pts
					(arc
						(start 216.18702 -360.764074)
						(mid 211.1629 -360.764074)
						(end 216.18702 -360.764074)
					)
				)
			)
		)
		(zone
			(layer "B.Cu")
			(hatch none 0.5)
			(connect_pads
				(clearance 0)
			)
			(min_thickness 0.25)
			(keepout
				(tracks not_allowed)
				(vias allowed)
				(pads allowed)
				(copperpour not_allowed)
				(footprints allowed)
			)
			(placement
				(enabled no)
				(sheetname "")
			)
			(fill
				(thermal_gap 0.5)
				(thermal_bridge_width 0.5)
				(island_removal_mode 0)
			)
			(polygon
				(pts
					(arc
						(start 213.67496 -365.285274)
						(mid 209.15376 -360.764074)
						(end 213.67496 -356.242874)
					)
					(arc
						(start 213.67496 -356.725474)
						(mid 209.63636 -360.764074)
						(end 213.67496 -364.802674)
					)
				)
			)
		)
		(zone
			(layer "B.Cu")
			(hatch none 0.5)
			(connect_pads
				(clearance 0)
			)
			(min_thickness 0.25)
			(keepout
				(tracks not_allowed)
				(vias allowed)
				(pads allowed)
				(copperpour not_allowed)
				(footprints allowed)
			)
			(placement
				(enabled no)
				(sheetname "")
			)
			(fill
				(thermal_gap 0.5)
				(thermal_bridge_width 0.5)
				(island_removal_mode 0)
			)
			(polygon
				(pts
					(arc
						(start 213.67496 -365.285274)
						(mid 218.19616 -360.764074)
						(end 213.67496 -356.242874)
					)
					(arc
						(start 213.67496 -356.725474)
						(mid 217.71356 -360.764074)
						(end 213.67496 -364.802674)
					)
				)
			)
		)
	)
)
